(kicad_pcb
	(version 20241229)
	(generator "pcbnew")
	(generator_version "9.0")
	(general
		(thickness 1.61)
		(legacy_teardrops no)
	)
	(paper "A3")
	(title_block
		(title "RDIMM DDR5 Tester")
		(date "2026-05-21")
		(rev "2.2.0")
		(company "Antmicro")
		(comment 9 "footprints 154-154 of 796")
	)
	(layers
		(0 "F.Cu" signal)
		(4 "In1.Cu" power)
		(6 "In2.Cu" mixed)
		(8 "In3.Cu" power)
		(10 "In4.Cu" mixed)
		(12 "In5.Cu" power)
		(14 "In6.Cu" mixed)
		(16 "In7.Cu" power)
		(18 "In8.Cu" power)
		(20 "In9.Cu" mixed)
		(22 "In10.Cu" power)
		(2 "B.Cu" signal)
		(9 "F.Adhes" user "F.Adhesive")
		(11 "B.Adhes" user "B.Adhesive")
		(13 "F.Paste" user)
		(15 "B.Paste" user)
		(5 "F.SilkS" user "F.Silkscreen")
		(7 "B.SilkS" user "B.Silkscreen")
		(1 "F.Mask" user)
		(3 "B.Mask" user)
		(17 "Dwgs.User" user "User.Drawings")
		(19 "Cmts.User" user "User.Comments")
		(21 "Eco1.User" user "User.Eco1")
		(23 "Eco2.User" user "User.Eco2")
		(25 "Edge.Cuts" user)
		(27 "Margin" user)
		(31 "F.CrtYd" user "F.Courtyard")
		(29 "B.CrtYd" user "B.Courtyard")
		(35 "F.Fab" user)
		(33 "B.Fab" user)
	)
	(footprint "antmicro-footprints:LGA-33_7x7mm_P0.65mm"
		(layer "F.Cu")
		(at 255.618 155.3085 -90)
		(property "Reference" "U20"
			(at 4.9915 4.868 0)
			(layer "F.SilkS")
			(effects
				(font
					(size 0.7 0.7)
					(thickness 0.15)
				)
				(justify left bottom)
			)
		)
		(property "Value" "MPM54304GMN"
			(at 0 5 90)
			(layer "F.Fab")
			(effects
				(font
					(size 0.7 0.7)
					(thickness 0.15)
				)
				(justify right bottom)
			)
		)
		(property "Datasheet" "https://www.monolithicpower.com/en/documentview/productdocument/index/version/2/document_type/Datasheet/lang/en/sku/MPM54304/document_id/4982/"
			(at 0 0 270)
			(layer "F.Fab")
			(hide yes)
			(effects
				(font
					(size 1.27 1.27)
					(thickness 0.15)
				)
			)
		)
		(property "MPN" "MPM54304GMN-0000"
			(at 0 0 270)
			(unlocked yes)
			(layer "F.Fab")
			(hide yes)
			(effects
				(font
					(size 1 1)
					(thickness 0.15)
				)
			)
		)
		(property "Manufacturer" "Monolithic Power Systems"
			(at 0 0 270)
			(unlocked yes)
			(layer "F.Fab")
			(hide yes)
			(effects
				(font
					(size 1 1)
					(thickness 0.15)
				)
			)
		)
		(property "Author" "Antmicro"
			(at 0 0 270)
			(unlocked yes)
			(layer "F.Fab")
			(hide yes)
			(effects
				(font
					(size 1 1)
					(thickness 0.15)
				)
			)
		)
		(property "License" "Apache-2.0"
			(at 0 0 270)
			(unlocked yes)
			(layer "F.Fab")
			(hide yes)
			(effects
				(font
					(size 1 1)
					(thickness 0.15)
				)
			)
		)
		(property ki_fp_filters "CP_48_13_ADI CP_48_13_ADI-M CP_48_13_ADI-L")
		(sheetname "/Supply/DC-DC IO/")
		(sheetfile "dc-dc-io.kicad_sch")
		(solder_paste_margin_ratio -0.1)
		(attr smd)
		(fp_line
			(start -3.65 3.648)
			(end -3.65 2.922)
			(stroke
				(width 0.15)
				(type solid)
			)
			(layer "F.SilkS")
		)
		(fp_line
			(start -2.926 3.648)
			(end -3.65 3.648)
			(stroke
				(width 0.15)
				(type solid)
			)
			(layer "F.SilkS")
		)
		(fp_line
			(start 2.922 3.648)
			(end 3.648 3.648)
			(stroke
				(width 0.15)
				(type solid)
			)
			(layer "F.SilkS")
		)
		(fp_line
			(start 3.648 3.648)
			(end 3.648 2.922)
			(stroke
				(width 0.15)
				(type solid)
			)
			(layer "F.SilkS")
		)
		(fp_line
			(start -3.665 -2.928)
			(end -3.665 -3.653)
			(stroke
				(width 0.15)
				(type solid)
			)
			(layer "F.SilkS")
		)
		(fp_line
			(start 2.922 -3.65)
			(end 3.648 -3.65)
			(stroke
				(width 0.15)
				(type solid)
			)
			(layer "F.SilkS")
		)
		(fp_line
			(start 3.648 -3.65)
			(end 3.648 -2.926)
			(stroke
				(width 0.15)
				(type solid)
			)
			(layer "F.SilkS")
		)
		(fp_line
			(start -3.665 -3.653)
			(end -2.94 -3.653)
			(stroke
				(width 0.15)
				(type solid)
			)
			(layer "F.SilkS")
		)
		(fp_circle
			(center -3.8 -1.925)
			(end -3.75 -1.925)
			(stroke
				(width 0.15)
				(type solid)
			)
			(fill yes)
			(layer "F.SilkS")
		)
		(fp_rect
			(start -4 -4)
			(end 3.999 3.999)
			(stroke
				(width 0.05)
				(type solid)
			)
			(fill no)
			(layer "F.CrtYd")
		)
		(fp_line
			(start -3.5 3.499)
			(end 3.499 3.499)
			(stroke
				(width 0.15)
				(type solid)
			)
			(layer "F.Fab")
		)
		(fp_line
			(start 3.499 3.499)
			(end 3.499 -3.5)
			(stroke
				(width 0.15)
				(type solid)
			)
			(layer "F.Fab")
		)
		(fp_line
			(start -3.5 -3.5)
			(end -3.5 3.499)
			(stroke
				(width 0.15)
				(type solid)
			)
			(layer "F.Fab")
		)
		(fp_line
			(start -3.101 -3.5)
			(end -3.5 -3.101)
			(stroke
				(width 0.15)
				(type solid)
			)
			(layer "F.Fab")
		)
		(fp_line
			(start 3.499 -3.5)
			(end -3.5 -3.5)
			(stroke
				(width 0.15)
				(type solid)
			)
			(layer "F.Fab")
		)
		(fp_text user "License: Apache-2.0"
			(at -4.35 9.699 270)
			(layer "F.Fab")
			(effects
				(font
					(size 0.7 0.7)
					(thickness 0.15)
				)
				(justify left bottom)
			)
		)
		(fp_text user "${REFERENCE}"
			(at -4.35 8.499 270)
			(layer "F.Fab")
			(effects
				(font
					(size 0.7 0.7)
					(thickness 0.15)
				)
				(justify left bottom)
			)
		)
		(fp_text user "Author: Antmicro"
			(at -4.35 7.299 270)
			(layer "F.Fab")
			(effects
				(font
					(size 0.7 0.7)
					(thickness 0.15)
				)
				(justify left bottom)
			)
		)
		(pad "1" smd rect
			(at -3.138 -1.625)
			(size 0.3 1.125)
			(layers "F.Cu" "F.Mask" "F.Paste")
			(net 158 "/Supply/DC-DC IO/VDDQ_local")
			(pinfunction "VOUT3")
			(pintype "power_out")
		)
		(pad "2" smd rect
			(at -3.138 -0.975)
			(size 0.3 1.125)
			(layers "F.Cu" "F.Mask" "F.Paste")
			(net 1 "GND")
			(pinfunction "GND")
			(pintype "passive")
		)
		(pad "3" smd rect
			(at -3.138 -0.328)
			(size 0.3 1.125)
			(layers "F.Cu" "F.Mask" "F.Paste")
			(net 533 "/I^{2}C + I3C/PWR.SDA")
			(pinfunction "SDA")
			(pintype "bidirectional")
		)
		(pad "4" smd rect
			(at -3.138 0.325)
			(size 0.3 1.125)
			(layers "F.Cu" "F.Mask" "F.Paste")
			(net 215 "/Supply/QDCDC2_SCL")
			(pinfunction "SCL")
			(pintype "input")
		)
		(pad "5" smd rect
			(at -3.138 0.972)
			(size 0.3 1.125)
			(layers "F.Cu" "F.Mask" "F.Paste")
			(net 1 "GND")
			(pinfunction "GND")
			(pintype "passive")
		)
		(pad "6" smd rect
			(at -3.138 1.624)
			(size 0.3 1.125)
			(layers "F.Cu" "F.Mask" "F.Paste")
			(net 715 "/Supply/DC-DC IO/FB6")
			(pinfunction "FB2")
			(pintype "input")
		)
		(pad "7" smd rect
			(at -2.926 3.136 90)
			(size 0.3 1.125)
			(layers "F.Cu" "F.Mask" "F.Paste")
			(net 1 "GND")
			(pinfunction "GND")
			(pintype "passive")
		)
		(pad "8" smd rect
			(at -2.275 3.136 90)
			(size 0.3 1.125)
			(layers "F.Cu" "F.Mask" "F.Paste")
			(net 46 "/Supply/DC-DC IO/5V_local")
			(pinfunction "VOUT2")
			(pintype "power_out")
		)
		(pad "9" smd rect
			(at -1.625 3.136 270)
			(size 0.3 1.125)
			(layers "F.Cu" "F.Mask" "F.Paste")
			(net 46 "/Supply/DC-DC IO/5V_local")
			(pinfunction "VOUT2")
			(pintype "passive")
		)
		(pad "10" smd rect
			(at -0.975 3.136 270)
			(size 0.3 1.125)
			(layers "F.Cu" "F.Mask" "F.Paste")
			(net 1 "GND")
			(pinfunction "GND")
			(pintype "passive")
		)
		(pad "11" smd rect
			(at -0.328 3.136 270)
			(size 0.3 1.125)
			(layers "F.Cu" "F.Mask" "F.Paste")
			(net 432 "unconnected-(U20-SW2-Pad11)")
			(pinfunction "SW2")
			(pintype "power_out+no_connect")
		)
		(pad "12" smd rect
			(at 0.325 3.136 270)
			(size 0.3 1.125)
			(layers "F.Cu" "F.Mask" "F.Paste")
			(net 433 "unconnected-(U20-SW1-Pad12)")
			(pinfunction "SW1")
			(pintype "power_out+no_connect")
		)
		(pad "13" smd rect
			(at 0.972 3.136 270)
			(size 0.3 1.125)
			(layers "F.Cu" "F.Mask" "F.Paste")
			(net 1 "GND")
			(pinfunction "GND")
			(pintype "passive")
		)
		(pad "14" smd rect
			(at 1.624 3.136 270)
			(size 0.3 1.125)
			(layers "F.Cu" "F.Mask" "F.Paste")
			(net 45 "/Supply/DC-DC IO/3V3_local")
			(pinfunction "VOUT1")
			(pintype "power_out")
		)
		(pad "15" smd rect
			(at 2.273 3.136 270)
			(size 0.3 1.125)
			(layers "F.Cu" "F.Mask" "F.Paste")
			(net 45 "/Supply/DC-DC IO/3V3_local")
			(pinfunction "VOUT1")
			(pintype "passive")
		)
		(pad "16" smd rect
			(at 2.922 3.136 270)
			(size 0.3 1.125)
			(layers "F.Cu" "F.Mask" "F.Paste")
			(net 1 "GND")
			(pinfunction "GND")
			(pintype "passive")
		)
		(pad "17" smd rect
			(at 3.136 1.624)
			(size 0.3 1.125)
			(layers "F.Cu" "F.Mask" "F.Paste")
			(net 1 "GND")
			(pinfunction "SGND1")
			(pintype "power_out")
		)
		(pad "18" smd rect
			(at 3.136 0.972)
			(size 0.3 1.125)
			(layers "F.Cu" "F.Mask" "F.Paste")
			(net 714 "/Supply/DC-DC IO/FB5")
			(pinfunction "FB1")
			(pintype "input")
		)
		(pad "19" smd rect
			(at 3.136 0.325)
			(size 0.3 1.125)
			(layers "F.Cu" "F.Mask" "F.Paste")
			(net 170 "/Supply/EN3")
			(pinfunction "EN/SYNCI")
			(pintype "input")
		)
		(pad "20" smd rect
			(at 3.136 -0.328)
			(size 0.3 1.125)
			(layers "F.Cu" "F.Mask" "F.Paste")
			(net 1 "GND")
			(pinfunction "GND")
			(pintype "passive")
		)
		(pad "21" smd rect
			(at 3.136 -0.975)
			(size 0.3 1.125)
			(layers "F.Cu" "F.Mask" "F.Paste")
			(net 1 "GND")
			(pinfunction "GND")
			(pintype "passive")
		)
		(pad "22" smd rect
			(at 3.136 -1.625)
			(size 0.3 1.125)
			(layers "F.Cu" "F.Mask" "F.Paste")
			(net 159 "/Supply/DC-DC IO/1V2_local")
			(pinfunction "VOUT4")
			(pintype "power_out")
		)
		(pad "23" smd rect
			(at 2.922 -3.138 90)
			(size 0.3 1.125)
			(layers "F.Cu" "F.Mask" "F.Paste")
			(net 159 "/Supply/DC-DC IO/1V2_local")
			(pinfunction "VOUT4")
			(pintype "passive")
		)
		(pad "24" smd rect
			(at 2.273 -3.138 90)
			(size 0.3 1.125)
			(layers "F.Cu" "F.Mask" "F.Paste")
			(net 719 "/Supply/DC-DC IO/FB8")
			(pinfunction "FB4")
			(pintype "input")
		)
		(pad "25" smd rect
			(at 1.624 -3.138 270)
			(size 0.3 1.125)
			(layers "F.Cu" "F.Mask" "F.Paste")
			(net 36 "/Supply/DC-DC IO/QDCDC2_VCC")
			(pinfunction "VCC")
			(pintype "input")
		)
		(pad "26" smd rect
			(at 0.972 -3.138 270)
			(size 0.3 1.125)
			(layers "F.Cu" "F.Mask" "F.Paste")
			(net 485 "PG3")
			(pinfunction "GPIO")
			(pintype "input")
		)
		(pad "27" smd rect
			(at 0.325 -3.138 270)
			(size 0.3 1.125)
			(layers "F.Cu" "F.Mask" "F.Paste")
			(net 1 "GND")
			(pinfunction "GND")
			(pintype "passive")
		)
		(pad "28" smd rect
			(at -0.328 -3.138 270)
			(size 0.3 1.125)
			(layers "F.Cu" "F.Mask" "F.Paste")
			(net 35 "VDC")
			(pinfunction "VIN")
			(pintype "input")
		)
		(pad "29" smd rect
			(at -0.975 -3.138 270)
			(size 0.3 1.125)
			(layers "F.Cu" "F.Mask" "F.Paste")
			(net 35 "VDC")
			(pinfunction "VIN")
			(pintype "passive")
		)
		(pad "30" smd rect
			(at -1.625 -3.138 270)
			(size 0.3 1.125)
			(layers "F.Cu" "F.Mask" "F.Paste")
			(net 1 "GND")
			(pinfunction "SGND2")
			(pintype "power_out")
		)
		(pad "31" smd rect
			(at -2.275 -3.138 270)
			(size 0.3 1.125)
			(layers "F.Cu" "F.Mask" "F.Paste")
			(net 718 "/Supply/DC-DC IO/FB7")
			(pinfunction "FB3")
			(pintype "input")
		)
		(pad "32" smd rect
			(at -2.926 -3.138 270)
			(size 0.3 1.125)
			(layers "F.Cu" "F.Mask" "F.Paste")
			(net 158 "/Supply/DC-DC IO/VDDQ_local")
			(pinfunction "VOUT3")
			(pintype "passive")
		)
		(pad "33" smd rect
			(at -0.863 -0.863 270)
			(size 1.725 1.725)
			(layers "F.Cu" "F.Mask" "F.Paste")
			(net 1 "GND")
			(pinfunction "GND")
			(pintype "passive")
			(solder_paste_margin -0.1)
		)
		(pad "33" smd rect
			(at -0.863 0.86 270)
			(size 1.725 1.725)
			(layers "F.Cu" "F.Mask" "F.Paste")
			(net 1 "GND")
			(pinfunction "GND")
			(pintype "passive")
			(solder_paste_margin -0.1)
		)
		(pad "33" smd rect
			(at 0.86 -0.863 270)
			(size 1.725 1.725)
			(layers "F.Cu" "F.Mask" "F.Paste")
			(net 1 "GND")
			(pinfunction "GND")
			(pintype "passive")
			(solder_paste_margin -0.1)
		)
		(pad "33" smd rect
			(at 0.86 0.86 270)
			(size 1.725 1.725)
			(layers "F.Cu" "F.Mask" "F.Paste")
			(net 1 "GND")
			(pinfunction "GND")
			(pintype "passive")
			(solder_paste_margin -0.1)
		)
	)
)
